# T6G (Grand Teton) — schematic netlist excerpt (pin names and nets, part order shuffled) for the footprints in the layout excerpt that follows; sources: Cadence DE-HDL packaged netlist, KiCad conversion of 04192023_DAF0TMB3IC0_F0TG_MB_C_brd_V02_OCP.brd

R9032  Q_RES  10K 1% CHIP  pkg 0402LF  page 136 : A = P3V3_AUX ; B = FM_PLD_OCP_SFF_AUX_PWR_EN
R8311  Q_RES  33 5% CHIP  pkg 0402LF  page 193 : A = PWRGD_PVDDCR_CPU0_P0 ; B = PWRGD_PVDDCR_CPU0_P0_R

(kicad_pcb
	(version 20260206)
	(generator "pcbnew")
	(generator_version "10.0")
	(general
		(thickness 1.6)
		(legacy_teardrops no)
	)
	(paper "A4")
	(title_block
		(title "04192023_DAF0TMB3IC0_F0TG_MB_C_brd_V02_OCP.brd")
		(comment 1 "Grand Teton / footprints 1450-1451 of 8354")
	)
	(layers
		(0 "F.Cu" signal "TOP")
		(4 "In1.Cu" signal "GND")
		(6 "In2.Cu" signal "IN1")
		(8 "In3.Cu" signal "GND1")
		(10 "In4.Cu" signal "IN2")
		(12 "In5.Cu" signal "GND2")
		(14 "In6.Cu" signal "IN3")
		(16 "In7.Cu" signal "GND3")
		(18 "In8.Cu" signal "VCC")
		(20 "In9.Cu" signal "VCC1")
		(22 "In10.Cu" signal "GND4")
		(24 "In11.Cu" signal "IN4")
		(26 "In12.Cu" signal "GND5")
		(28 "In13.Cu" signal "IN5")
		(30 "In14.Cu" signal "GND6")
		(32 "In15.Cu" signal "IN6")
		(34 "In16.Cu" signal "GND7")
		(2 "B.Cu" signal "BOTTOM")
		(9 "F.Adhes" user "F.Adhesive")
		(11 "B.Adhes" user "B.Adhesive")
		(13 "F.Paste" user "Package Geometry/Pastemask Top")
		(15 "B.Paste" user "Package Geometry/Pastemask Bottom")
		(5 "F.SilkS" user "Ref Des/Silkscreen Top")
		(7 "B.SilkS" user "Ref Des/Silkscreen Bottom")
		(1 "F.Mask" user "Board Geometry/Soldermask Top")
		(3 "B.Mask" user "Board Geometry/Soldermask Bottom")
		(17 "Dwgs.User" user "User.Drawings")
		(19 "Cmts.User" user "User.Comments")
		(21 "Eco1.User" user "User.Eco1")
		(23 "Eco2.User" user "User.Eco2")
		(25 "Edge.Cuts" user "Board Geometry/Outline")
		(27 "Margin" user)
		(31 "F.CrtYd" user "Package Geometry/Place Bound Top")
		(29 "B.CrtYd" user "Package Geometry/Place Bound Bottom")
		(35 "F.Fab" user "Ref Des/Assembly Top")
		(33 "B.Fab" user "Ref Des/Assembly Bottom")
	)
	(footprint ""
		(layer "F.Cu")
		(at 212.725 -99.822)
		(property "Reference" "R9032"
			(at 0 0 0)
			(layer "F.SilkS")
			(hide yes)
			(effects
				(font
					(size 1.27 1.27)
				)
			)
		)
		(property "Value" ""
			(at 0 0 0)
			(layer "F.Fab")
			(effects
				(font
					(size 1.27 1.27)
				)
			)
		)
		(duplicate_pad_numbers_are_jumpers no)
		(fp_line
			(start -0.7874 -0.4064)
			(end 0.7874 -0.4064)
			(stroke
				(width 0.1524)
				(type default)
			)
			(layer "F.SilkS")
		)
		(fp_line
			(start -0.7874 0.4064)
			(end -0.7874 -0.4064)
			(stroke
				(width 0.1524)
				(type default)
			)
			(layer "F.SilkS")
		)
		(fp_line
			(start 0.7874 -0.4064)
			(end 0.7874 0.4064)
			(stroke
				(width 0.1524)
				(type default)
			)
			(layer "F.SilkS")
		)
		(fp_line
			(start 0.7874 0.4064)
			(end -0.7874 0.4064)
			(stroke
				(width 0.1524)
				(type default)
			)
			(layer "F.SilkS")
		)
		(fp_line
			(start -0.67945 -0.305054)
			(end -0.12065 -0.305054)
			(stroke
				(width 0.1)
				(type default)
			)
			(layer "F.Fab")
		)
		(fp_line
			(start -0.67945 0.3048)
			(end -0.67945 -0.305054)
			(stroke
				(width 0.1)
				(type default)
			)
			(layer "F.Fab")
		)
		(fp_line
			(start -0.12065 -0.305054)
			(end -0.12065 -0.2794)
			(stroke
				(width 0.1)
				(type default)
			)
			(layer "F.Fab")
		)
		(fp_line
			(start -0.12065 -0.2794)
			(end 0.12065 -0.2794)
			(stroke
				(width 0.1)
				(type default)
			)
			(layer "F.Fab")
		)
		(fp_line
			(start -0.12065 0.2794)
			(end -0.12065 0.3048)
			(stroke
				(width 0.1)
				(type default)
			)
			(layer "F.Fab")
		)
		(fp_line
			(start -0.12065 0.3048)
			(end -0.67945 0.3048)
			(stroke
				(width 0.1)
				(type default)
			)
			(layer "F.Fab")
		)
		(fp_line
			(start 0.120396 0.2794)
			(end -0.12065 0.2794)
			(stroke
				(width 0.1)
				(type default)
			)
			(layer "F.Fab")
		)
		(fp_line
			(start 0.120396 0.3048)
			(end 0.120396 0.2794)
			(stroke
				(width 0.1)
				(type default)
			)
			(layer "F.Fab")
		)
		(fp_line
			(start 0.12065 -0.3048)
			(end 0.67945 -0.3048)
			(stroke
				(width 0.1)
				(type default)
			)
			(layer "F.Fab")
		)
		(fp_line
			(start 0.12065 -0.2794)
			(end 0.12065 -0.3048)
			(stroke
				(width 0.1)
				(type default)
			)
			(layer "F.Fab")
		)
		(fp_line
			(start 0.67945 -0.3048)
			(end 0.67945 0.3048)
			(stroke
				(width 0.1)
				(type default)
			)
			(layer "F.Fab")
		)
		(fp_line
			(start 0.67945 0.3048)
			(end 0.120396 0.3048)
			(stroke
				(width 0.1)
				(type default)
			)
			(layer "F.Fab")
		)
		(pad "1" smd circle
			(at -0.40005 0)
			(size 0 0)
			(layers "F.Cu" "F.Mask" "F.Paste")
			(net "P3V3_AUX")
		)
		(pad "2" smd circle
			(at 0.40005 0)
			(size 0 0)
			(layers "F.Cu" "F.Mask" "F.Paste")
			(net "FM_PLD_OCP_SFF_AUX_PWR_EN")
		)
	)
	(footprint ""
		(layer "F.Cu")
		(at 372.937278 -139.440158)
		(property "Reference" "R8311"
			(at 0 0 0)
			(layer "F.SilkS")
			(hide yes)
			(effects
				(font
					(size 1.27 1.27)
				)
			)
		)
		(property "Value" ""
			(at 0 0 0)
			(layer "F.Fab")
			(effects
				(font
					(size 1.27 1.27)
				)
			)
		)
		(duplicate_pad_numbers_are_jumpers no)
		(fp_line
			(start -0.7874 -0.4064)
			(end 0.7874 -0.4064)
			(stroke
				(width 0.1524)
				(type default)
			)
			(layer "F.SilkS")
		)
		(fp_line
			(start -0.7874 0.4064)
			(end -0.7874 -0.4064)
			(stroke
				(width 0.1524)
				(type default)
			)
			(layer "F.SilkS")
		)
		(fp_line
			(start 0.7874 -0.4064)
			(end 0.7874 0.4064)
			(stroke
				(width 0.1524)
				(type default)
			)
			(layer "F.SilkS")
		)
		(fp_line
			(start 0.7874 0.4064)
			(end -0.7874 0.4064)
			(stroke
				(width 0.1524)
				(type default)
			)
			(layer "F.SilkS")
		)
		(fp_line
			(start -0.67945 -0.305054)
			(end -0.12065 -0.305054)
			(stroke
				(width 0.1)
				(type default)
			)
			(layer "F.Fab")
		)
		(fp_line
			(start -0.67945 0.3048)
			(end -0.67945 -0.305054)
			(stroke
				(width 0.1)
				(type default)
			)
			(layer "F.Fab")
		)
		(fp_line
			(start -0.12065 -0.305054)
			(end -0.12065 -0.2794)
			(stroke
				(width 0.1)
				(type default)
			)
			(layer "F.Fab")
		)
		(fp_line
			(start -0.12065 -0.2794)
			(end 0.12065 -0.2794)
			(stroke
				(width 0.1)
				(type default)
			)
			(layer "F.Fab")
		)
		(fp_line
			(start -0.12065 0.2794)
			(end -0.12065 0.3048)
			(stroke
				(width 0.1)
				(type default)
			)
			(layer "F.Fab")
		)
		(fp_line
			(start -0.12065 0.3048)
			(end -0.67945 0.3048)
			(stroke
				(width 0.1)
				(type default)
			)
			(layer "F.Fab")
		)
		(fp_line
			(start 0.120396 0.2794)
			(end -0.12065 0.2794)
			(stroke
				(width 0.1)
				(type default)
			)
			(layer "F.Fab")
		)
		(fp_line
			(start 0.120396 0.3048)
			(end 0.120396 0.2794)
			(stroke
				(width 0.1)
				(type default)
			)
			(layer "F.Fab")
		)
		(fp_line
			(start 0.12065 -0.3048)
			(end 0.67945 -0.3048)
			(stroke
				(width 0.1)
				(type default)
			)
			(layer "F.Fab")
		)
		(fp_line
			(start 0.12065 -0.2794)
			(end 0.12065 -0.3048)
			(stroke
				(width 0.1)
				(type default)
			)
			(layer "F.Fab")
		)
		(fp_line
			(start 0.67945 -0.3048)
			(end 0.67945 0.3048)
			(stroke
				(width 0.1)
				(type default)
			)
			(layer "F.Fab")
		)
		(fp_line
			(start 0.67945 0.3048)
			(end 0.120396 0.3048)
			(stroke
				(width 0.1)
				(type default)
			)
			(layer "F.Fab")
		)
		(pad "1" smd circle
			(at -0.40005 0)
			(size 0 0)
			(layers "F.Cu" "F.Mask" "F.Paste")
			(net "PWRGD_PVDDCR_CPU0_P0")
		)
		(pad "2" smd circle
			(at 0.40005 0)
			(size 0 0)
			(layers "F.Cu" "F.Mask" "F.Paste")
			(net "PWRGD_PVDDCR_CPU0_P0_R")
		)
	)
)
